(kicad_pcb
	(version 20260206)
	(generator "pcbnew")
	(generator_version "10.0")
	(general
		(thickness 1.6)
		(legacy_teardrops no)
	)
	(paper "A4")
	(title_block
		(title "04192023_DAF0TMB3IC0_F0TG_MB_C_brd_V02_OCP.brd")
		(comment 1 "Grand Teton / footprints 3878-3883 of 8354")
	)
	(layers
		(0 "F.Cu" signal "TOP")
		(4 "In1.Cu" signal "GND")
		(6 "In2.Cu" signal "IN1")
		(8 "In3.Cu" signal "GND1")
		(10 "In4.Cu" signal "IN2")
		(12 "In5.Cu" signal "GND2")
		(14 "In6.Cu" signal "IN3")
		(16 "In7.Cu" signal "GND3")
		(18 "In8.Cu" signal "VCC")
		(20 "In9.Cu" signal "VCC1")
		(22 "In10.Cu" signal "GND4")
		(24 "In11.Cu" signal "IN4")
		(26 "In12.Cu" signal "GND5")
		(28 "In13.Cu" signal "IN5")
		(30 "In14.Cu" signal "GND6")
		(32 "In15.Cu" signal "IN6")
		(34 "In16.Cu" signal "GND7")
		(2 "B.Cu" signal "BOTTOM")
		(9 "F.Adhes" user "F.Adhesive")
		(11 "B.Adhes" user "B.Adhesive")
		(13 "F.Paste" user "Package Geometry/Pastemask Top")
		(15 "B.Paste" user "Package Geometry/Pastemask Bottom")
		(5 "F.SilkS" user "Ref Des/Silkscreen Top")
		(7 "B.SilkS" user "Ref Des/Silkscreen Bottom")
		(1 "F.Mask" user "Board Geometry/Soldermask Top")
		(3 "B.Mask" user "Board Geometry/Soldermask Bottom")
		(17 "Dwgs.User" user "User.Drawings")
		(19 "Cmts.User" user "User.Comments")
		(21 "Eco1.User" user "User.Eco1")
		(23 "Eco2.User" user "User.Eco2")
		(25 "Edge.Cuts" user "Board Geometry/Outline")
		(27 "Margin" user)
		(31 "F.CrtYd" user "Package Geometry/Place Bound Top")
		(29 "B.CrtYd" user "Package Geometry/Place Bound Bottom")
		(35 "F.Fab" user "Ref Des/Assembly Top")
		(33 "B.Fab" user "Ref Des/Assembly Bottom")
	)
	(footprint ""
		(layer "F.Cu")
		(at 189.357 -51.054 90)
		(property "Reference" "R8031"
			(at 0 0 90)
			(layer "F.SilkS")
			(hide yes)
			(effects
				(font
					(size 1.27 1.27)
				)
			)
		)
		(property "Value" ""
			(at 0 0 90)
			(layer "F.Fab")
			(effects
				(font
					(size 1.27 1.27)
				)
			)
		)
		(duplicate_pad_numbers_are_jumpers no)
		(fp_line
			(start 0.7874 -0.4064)
			(end 0.7874 0.4064)
			(stroke
				(width 0.1524)
				(type default)
			)
			(layer "F.SilkS")
		)
		(fp_line
			(start -0.7874 -0.4064)
			(end 0.7874 -0.4064)
			(stroke
				(width 0.1524)
				(type default)
			)
			(layer "F.SilkS")
		)
		(fp_line
			(start 0.7874 0.4064)
			(end -0.7874 0.4064)
			(stroke
				(width 0.1524)
				(type default)
			)
			(layer "F.SilkS")
		)
		(fp_line
			(start -0.7874 0.4064)
			(end -0.7874 -0.4064)
			(stroke
				(width 0.1524)
				(type default)
			)
			(layer "F.SilkS")
		)
		(fp_line
			(start -0.12065 -0.305054)
			(end -0.12065 -0.2794)
			(stroke
				(width 0.1)
				(type default)
			)
			(layer "F.Fab")
		)
		(fp_line
			(start -0.67945 -0.305054)
			(end -0.12065 -0.305054)
			(stroke
				(width 0.1)
				(type default)
			)
			(layer "F.Fab")
		)
		(fp_line
			(start 0.67945 -0.3048)
			(end 0.67945 0.3048)
			(stroke
				(width 0.1)
				(type default)
			)
			(layer "F.Fab")
		)
		(fp_line
			(start 0.12065 -0.3048)
			(end 0.67945 -0.3048)
			(stroke
				(width 0.1)
				(type default)
			)
			(layer "F.Fab")
		)
		(fp_line
			(start 0.12065 -0.2794)
			(end 0.12065 -0.3048)
			(stroke
				(width 0.1)
				(type default)
			)
			(layer "F.Fab")
		)
		(fp_line
			(start -0.12065 -0.2794)
			(end 0.12065 -0.2794)
			(stroke
				(width 0.1)
				(type default)
			)
			(layer "F.Fab")
		)
		(fp_line
			(start 0.120396 0.2794)
			(end -0.12065 0.2794)
			(stroke
				(width 0.1)
				(type default)
			)
			(layer "F.Fab")
		)
		(fp_line
			(start -0.12065 0.2794)
			(end -0.12065 0.3048)
			(stroke
				(width 0.1)
				(type default)
			)
			(layer "F.Fab")
		)
		(fp_line
			(start 0.67945 0.3048)
			(end 0.120396 0.3048)
			(stroke
				(width 0.1)
				(type default)
			)
			(layer "F.Fab")
		)
		(fp_line
			(start 0.120396 0.3048)
			(end 0.120396 0.2794)
			(stroke
				(width 0.1)
				(type default)
			)
			(layer "F.Fab")
		)
		(fp_line
			(start -0.12065 0.3048)
			(end -0.67945 0.3048)
			(stroke
				(width 0.1)
				(type default)
			)
			(layer "F.Fab")
		)
		(fp_line
			(start -0.67945 0.3048)
			(end -0.67945 -0.305054)
			(stroke
				(width 0.1)
				(type default)
			)
			(layer "F.Fab")
		)
		(pad "1" smd circle
			(at -0.40005 0 90)
			(size 0 0)
			(layers "F.Cu" "F.Mask" "F.Paste")
			(net "P12V_SCM_FLTB_N")
		)
		(pad "2" smd circle
			(at 0.40005 0 90)
			(size 0 0)
			(layers "F.Cu" "F.Mask" "F.Paste")
			(net "P12V_SCM_FAULT_R_N")
		)
	)
	(footprint ""
		(layer "F.Cu")
		(at 396.250668 -400.903694)
		(property "Reference" "L21"
			(at -3.06197 -1.343914 90)
			(unlocked yes)
			(layer "F.SilkS")
			(effects
				(font
					(size 0.7874 0.5842)
					(thickness 0.1524)
				)
				(justify left)
			)
		)
		(property "Value" ""
			(at 0 0 0)
			(layer "F.Fab")
			(effects
				(font
					(size 1.27 1.27)
				)
			)
		)
		(duplicate_pad_numbers_are_jumpers no)
		(fp_line
			(start -2.249932 -2.249932)
			(end 2.249932 -2.249932)
			(stroke
				(width 0.1524)
				(type default)
			)
			(layer "F.SilkS")
		)
		(fp_line
			(start -2.249932 -1.3843)
			(end -2.249932 -2.249932)
			(stroke
				(width 0.1524)
				(type default)
			)
			(layer "F.SilkS")
		)
		(fp_line
			(start -2.249932 2.249932)
			(end -2.249932 1.3843)
			(stroke
				(width 0.1524)
				(type default)
			)
			(layer "F.SilkS")
		)
		(fp_line
			(start 2.249932 -2.249932)
			(end 2.249932 -1.3843)
			(stroke
				(width 0.1524)
				(type default)
			)
			(layer "F.SilkS")
		)
		(fp_line
			(start 2.249932 1.3843)
			(end 2.249932 2.249932)
			(stroke
				(width 0.1524)
				(type default)
			)
			(layer "F.SilkS")
		)
		(fp_line
			(start 2.249932 2.249932)
			(end -2.249932 2.249932)
			(stroke
				(width 0.1524)
				(type default)
			)
			(layer "F.SilkS")
		)
		(fp_line
			(start -2.249932 -2.249932)
			(end 2.249932 -2.249932)
			(stroke
				(width 0.1)
				(type default)
			)
			(layer "F.Fab")
		)
		(fp_line
			(start -2.249932 2.249932)
			(end -2.249932 -2.249932)
			(stroke
				(width 0.1)
				(type default)
			)
			(layer "F.Fab")
		)
		(fp_line
			(start 2.249932 -2.249932)
			(end 2.249932 2.249932)
			(stroke
				(width 0.1)
				(type default)
			)
			(layer "F.Fab")
		)
		(fp_line
			(start 2.249932 2.249932)
			(end -2.249932 2.249932)
			(stroke
				(width 0.1)
				(type default)
			)
			(layer "F.Fab")
		)
		(pad "1" smd rect
			(at -1.82499 0)
			(size 1.0668 2.5146)
			(layers "F.Cu" "F.Mask" "F.Paste")
			(net "P0V9_CPU0_RT_2D")
		)
		(pad "2" smd rect
			(at 1.82499 0)
			(size 1.0668 2.5146)
			(layers "F.Cu" "F.Mask" "F.Paste")
			(net "P0V9_CPU0_RT2_2A")
		)
	)
	(footprint ""
		(layer "F.Cu")
		(at 290.890198 -395.231366 90)
		(property "Reference" "U48"
			(at 0.91948 3.869182 90)
			(unlocked yes)
			(layer "F.SilkS")
			(effects
				(font
					(size 0.7874 0.5842)
					(thickness 0.1524)
				)
			)
		)
		(property "Value" ""
			(at 0 0 90)
			(layer "F.Fab")
			(effects
				(font
					(size 1.27 1.27)
				)
			)
		)
		(duplicate_pad_numbers_are_jumpers no)
		(fp_line
			(start 1.03378 -1.284478)
			(end 1.03378 1.284478)
			(stroke
				(width 0.1524)
				(type default)
			)
			(layer "F.SilkS")
		)
		(fp_line
			(start -1.03378 -1.284478)
			(end 1.03378 -1.284478)
			(stroke
				(width 0.1524)
				(type default)
			)
			(layer "F.SilkS")
		)
		(fp_line
			(start 1.03378 1.284478)
			(end -1.03378 1.284478)
			(stroke
				(width 0.1524)
				(type default)
			)
			(layer "F.SilkS")
		)
		(fp_line
			(start -1.03378 1.284478)
			(end -1.03378 -1.284478)
			(stroke
				(width 0.1524)
				(type default)
			)
			(layer "F.SilkS")
		)
		(fp_poly
			(pts
				(xy -1.23952 -1.219454) (xy -1.894586 -1.387602) (xy -1.498092 -1.844548)
			)
			(stroke
				(width 0)
				(type default)
			)
			(fill yes)
			(layer "F.SilkS")
		)
		(fp_line
			(start 0.774954 -1.02489)
			(end 0.774954 1.02489)
			(stroke
				(width 0.1)
				(type default)
			)
			(layer "F.Fab")
		)
		(fp_line
			(start -0.774954 -1.02489)
			(end 0.774954 -1.02489)
			(stroke
				(width 0.1)
				(type default)
			)
			(layer "F.Fab")
		)
		(fp_line
			(start 0.774954 1.02489)
			(end -0.774954 1.02489)
			(stroke
				(width 0.1)
				(type default)
			)
			(layer "F.Fab")
		)
		(fp_line
			(start -0.774954 1.02489)
			(end -0.774954 -1.02489)
			(stroke
				(width 0.1)
				(type default)
			)
			(layer "F.Fab")
		)
		(fp_poly
			(pts
				(xy -1.201674 -0.750062) (xy -1.806702 -0.447548) (xy -1.806702 -1.052576)
			)
			(stroke
				(width 0)
				(type default)
			)
			(fill yes)
			(layer "F.Fab")
		)
		(pad "1" smd rect
			(at -0.64008 -0.750062 180)
			(size 0.3048 0.5334)
			(layers "F.Cu" "F.Mask" "F.Paste")
			(net "SMB_RT_CPU0_P1_ROM_MUX_1D_SCL")
		)
		(pad "2" smd rect
			(at -0.64008 -0.249936 180)
			(size 0.254 0.5334)
			(layers "F.Cu" "F.Mask" "F.Paste")
			(net "SMB_RT_CPU0_P1_ROM_MUX_1D_SDA")
		)
		(pad "3" smd rect
			(at -0.64008 0.249936 180)
			(size 0.254 0.5334)
			(layers "F.Cu" "F.Mask" "F.Paste")
			(net "SMB_RT_CPU0_P1_ROM_MUX_2D_SCL")
		)
		(pad "4" smd rect
			(at -0.64008 0.750062 180)
			(size 0.3048 0.5334)
			(layers "F.Cu" "F.Mask" "F.Paste")
			(net "SMB_RT_CPU0_P1_ROM_MUX_2D_SDA")
		)
		(pad "5" smd rect
			(at 0 0.839978 90)
			(size 0.3302 0.635)
			(layers "F.Cu" "F.Mask" "F.Paste")
			(net "GND")
		)
		(pad "6" smd rect
			(at 0.64008 0.750062 180)
			(size 0.3048 0.5334)
			(layers "F.Cu" "F.Mask" "F.Paste")
			(net "RT_ROM_MUX6_OE_N")
		)
		(pad "7" smd rect
			(at 0.64008 0.249936 180)
			(size 0.254 0.5334)
			(layers "F.Cu" "F.Mask" "F.Paste")
			(net "SMB_RT_CPU0_P1_ROM_R_SDA")
		)
		(pad "8" smd rect
			(at 0.64008 -0.249936 180)
			(size 0.254 0.5334)
			(layers "F.Cu" "F.Mask" "F.Paste")
			(net "SMB_RT_CPU0_P1_ROM_R_SCL")
		)
		(pad "9" smd rect
			(at 0.64008 -0.750062 180)
			(size 0.3048 0.5334)
			(layers "F.Cu" "F.Mask" "F.Paste")
			(net "FM_SMB_RT_ROM_MUX6_SEL")
		)
		(pad "10" smd rect
			(at 0 -0.839978 90)
			(size 0.3302 0.635)
			(layers "F.Cu" "F.Mask" "F.Paste")
			(net "P3V3_AUX")
		)
	)
	(footprint ""
		(layer "F.Cu")
		(at 369.330478 -159.907732 -90)
		(property "Reference" "PL53"
			(at -0.072136 3.778504 90)
			(unlocked yes)
			(layer "F.SilkS")
			(effects
				(font
					(size 0.7874 0.5842)
					(thickness 0.1524)
				)
				(justify left)
			)
		)
		(property "Value" ""
			(at 0 0 270)
			(layer "F.Fab")
			(effects
				(font
					(size 1.27 1.27)
				)
			)
		)
		(duplicate_pad_numbers_are_jumpers no)
		(fp_line
			(start -3.050032 2.999994)
			(end 3.050032 2.999994)
			(stroke
				(width 0.1524)
				(type default)
			)
			(layer "F.SilkS")
		)
		(fp_line
			(start 3.050032 2.999994)
			(end 3.050032 1.4478)
			(stroke
				(width 0.1524)
				(type default)
			)
			(layer "F.SilkS")
		)
		(fp_line
			(start -3.050032 1.4478)
			(end -3.050032 2.999994)
			(stroke
				(width 0.1524)
				(type default)
			)
			(layer "F.SilkS")
		)
		(fp_line
			(start 3.050032 -1.4478)
			(end 3.050032 -2.999994)
			(stroke
				(width 0.1524)
				(type default)
			)
			(layer "F.SilkS")
		)
		(fp_line
			(start -3.050032 -2.999994)
			(end -3.050032 -1.4478)
			(stroke
				(width 0.1524)
				(type default)
			)
			(layer "F.SilkS")
		)
		(fp_line
			(start 3.050032 -2.999994)
			(end -3.050032 -2.999994)
			(stroke
				(width 0.1524)
				(type default)
			)
			(layer "F.SilkS")
		)
		(fp_line
			(start -3.050032 2.999994)
			(end 3.050032 2.999994)
			(stroke
				(width 0.1)
				(type default)
			)
			(layer "F.Fab")
		)
		(fp_line
			(start 3.050032 2.999994)
			(end 3.050032 -2.999994)
			(stroke
				(width 0.1)
				(type default)
			)
			(layer "F.Fab")
		)
		(fp_line
			(start -3.050032 -2.999994)
			(end -3.050032 2.999994)
			(stroke
				(width 0.1)
				(type default)
			)
			(layer "F.Fab")
		)
		(fp_line
			(start 3.050032 -2.999994)
			(end -3.050032 -2.999994)
			(stroke
				(width 0.1)
				(type default)
			)
			(layer "F.Fab")
		)
		(pad "1" smd rect
			(at -2.525014 0 270)
			(size 1.651 2.6162)
			(layers "F.Cu" "F.Mask" "F.Paste")
			(net "SW_P12V_AUX_PVDDCR_CPU0_P0_FLT")
		)
		(pad "2" smd rect
			(at 2.525014 0 270)
			(size 1.651 2.6162)
			(layers "F.Cu" "F.Mask" "F.Paste")
			(net "P12V_AUX")
		)
	)
	(footprint ""
		(layer "F.Cu")
		(at 405.388572 -163.942014 -90)
		(property "Reference" "PR361"
			(at 0 0 270)
			(layer "F.SilkS")
			(hide yes)
			(effects
				(font
					(size 1.27 1.27)
				)
			)
		)
		(property "Value" ""
			(at 0 0 270)
			(layer "F.Fab")
			(effects
				(font
					(size 1.27 1.27)
				)
			)
		)
		(duplicate_pad_numbers_are_jumpers no)
		(fp_line
			(start -0.7874 0.4064)
			(end -0.7874 -0.4064)
			(stroke
				(width 0.1524)
				(type default)
			)
			(layer "F.SilkS")
		)
		(fp_line
			(start 0.7874 0.4064)
			(end -0.7874 0.4064)
			(stroke
				(width 0.1524)
				(type default)
			)
			(layer "F.SilkS")
		)
		(fp_line
			(start -0.7874 -0.4064)
			(end 0.7874 -0.4064)
			(stroke
				(width 0.1524)
				(type default)
			)
			(layer "F.SilkS")
		)
		(fp_line
			(start 0.7874 -0.4064)
			(end 0.7874 0.4064)
			(stroke
				(width 0.1524)
				(type default)
			)
			(layer "F.SilkS")
		)
		(fp_line
			(start -0.67945 0.3048)
			(end -0.67945 -0.305054)
			(stroke
				(width 0.1)
				(type default)
			)
			(layer "F.Fab")
		)
		(fp_line
			(start -0.12065 0.3048)
			(end -0.67945 0.3048)
			(stroke
				(width 0.1)
				(type default)
			)
			(layer "F.Fab")
		)
		(fp_line
			(start 0.120396 0.3048)
			(end 0.120396 0.2794)
			(stroke
				(width 0.1)
				(type default)
			)
			(layer "F.Fab")
		)
		(fp_line
			(start 0.67945 0.3048)
			(end 0.120396 0.3048)
			(stroke
				(width 0.1)
				(type default)
			)
			(layer "F.Fab")
		)
		(fp_line
			(start -0.12065 0.2794)
			(end -0.12065 0.3048)
			(stroke
				(width 0.1)
				(type default)
			)
			(layer "F.Fab")
		)
		(fp_line
			(start 0.120396 0.2794)
			(end -0.12065 0.2794)
			(stroke
				(width 0.1)
				(type default)
			)
			(layer "F.Fab")
		)
		(fp_line
			(start -0.12065 -0.2794)
			(end 0.12065 -0.2794)
			(stroke
				(width 0.1)
				(type default)
			)
			(layer "F.Fab")
		)
		(fp_line
			(start 0.12065 -0.2794)
			(end 0.12065 -0.3048)
			(stroke
				(width 0.1)
				(type default)
			)
			(layer "F.Fab")
		)
		(fp_line
			(start 0.12065 -0.3048)
			(end 0.67945 -0.3048)
			(stroke
				(width 0.1)
				(type default)
			)
			(layer "F.Fab")
		)
		(fp_line
			(start 0.67945 -0.3048)
			(end 0.67945 0.3048)
			(stroke
				(width 0.1)
				(type default)
			)
			(layer "F.Fab")
		)
		(fp_line
			(start -0.67945 -0.305054)
			(end -0.12065 -0.305054)
			(stroke
				(width 0.1)
				(type default)
			)
			(layer "F.Fab")
		)
		(fp_line
			(start -0.12065 -0.305054)
			(end -0.12065 -0.2794)
			(stroke
				(width 0.1)
				(type default)
			)
			(layer "F.Fab")
		)
		(pad "1" smd circle
			(at -0.40005 0 270)
			(size 0 0)
			(layers "F.Cu" "F.Mask" "F.Paste")
			(net "SW_PVDDCR_SOC_P0_BOOT2")
		)
		(pad "2" smd circle
			(at 0.40005 0 270)
			(size 0 0)
			(layers "F.Cu" "F.Mask" "F.Paste")
			(net "SW_PVDDCR_SOC_P0_BOOT2_RC")
		)
	)
	(footprint ""
		(layer "F.Cu")
		(at 358.467152 -261.747762 -90)
		(property "Reference" "C2156"
			(at 0 0 270)
			(layer "F.SilkS")
			(hide yes)
			(effects
				(font
					(size 1.27 1.27)
				)
			)
		)
		(property "Value" ""
			(at 0 0 270)
			(layer "F.Fab")
			(effects
				(font
					(size 1.27 1.27)
				)
			)
		)
		(duplicate_pad_numbers_are_jumpers no)
		(fp_line
			(start -0.7874 0.4064)
			(end -0.7874 -0.4064)
			(stroke
				(width 0.1524)
				(type default)
			)
			(layer "F.SilkS")
		)
		(fp_line
			(start 0.7874 0.4064)
			(end -0.7874 0.4064)
			(stroke
				(width 0.1524)
				(type default)
			)
			(layer "F.SilkS")
		)
		(fp_line
			(start -0.7874 -0.4064)
			(end 0.7874 -0.4064)
			(stroke
				(width 0.1524)
				(type default)
			)
			(layer "F.SilkS")
		)
		(fp_line
			(start 0.7874 -0.4064)
			(end 0.7874 0.4064)
			(stroke
				(width 0.1524)
				(type default)
			)
			(layer "F.SilkS")
		)
		(fp_line
			(start -0.67945 0.3048)
			(end -0.67945 -0.305054)
			(stroke
				(width 0.1)
				(type default)
			)
			(layer "F.Fab")
		)
		(fp_line
			(start -0.12065 0.3048)
			(end -0.67945 0.3048)
			(stroke
				(width 0.1)
				(type default)
			)
			(layer "F.Fab")
		)
		(fp_line
			(start 0.120396 0.3048)
			(end 0.120396 0.2794)
			(stroke
				(width 0.1)
				(type default)
			)
			(layer "F.Fab")
		)
		(fp_line
			(start 0.67945 0.3048)
			(end 0.120396 0.3048)
			(stroke
				(width 0.1)
				(type default)
			)
			(layer "F.Fab")
		)
		(fp_line
			(start -0.12065 0.2794)
			(end -0.12065 0.3048)
			(stroke
				(width 0.1)
				(type default)
			)
			(layer "F.Fab")
		)
		(fp_line
			(start 0.120396 0.2794)
			(end -0.12065 0.2794)
			(stroke
				(width 0.1)
				(type default)
			)
			(layer "F.Fab")
		)
		(fp_line
			(start -0.12065 -0.2794)
			(end 0.12065 -0.2794)
			(stroke
				(width 0.1)
				(type default)
			)
			(layer "F.Fab")
		)
		(fp_line
			(start 0.12065 -0.2794)
			(end 0.12065 -0.3048)
			(stroke
				(width 0.1)
				(type default)
			)
			(layer "F.Fab")
		)
		(fp_line
			(start 0.12065 -0.3048)
			(end 0.67945 -0.3048)
			(stroke
				(width 0.1)
				(type default)
			)
			(layer "F.Fab")
		)
		(fp_line
			(start 0.67945 -0.3048)
			(end 0.67945 0.3048)
			(stroke
				(width 0.1)
				(type default)
			)
			(layer "F.Fab")
		)
		(fp_line
			(start -0.67945 -0.305054)
			(end -0.12065 -0.305054)
			(stroke
				(width 0.1)
				(type default)
			)
			(layer "F.Fab")
		)
		(fp_line
			(start -0.12065 -0.305054)
			(end -0.12065 -0.2794)
			(stroke
				(width 0.1)
				(type default)
			)
			(layer "F.Fab")
		)
		(pad "1" smd circle
			(at -0.40005 0 270)
			(size 0 0)
			(layers "F.Cu" "F.Mask" "F.Paste")
			(net "PVDD11_S3_P0")
		)
		(pad "2" smd circle
			(at 0.40005 0 270)
			(size 0 0)
			(layers "F.Cu" "F.Mask" "F.Paste")
			(net "GND")
		)
	)
)
